(kicad_pcb
	(version 20260206)
	(generator "pcbnew")
	(generator_version "10.0")
	(general
		(thickness 1.6)
		(legacy_teardrops no)
	)
	(paper "A4")
	(title_block
		(title "03242023_DA0F0TMBIJ0_F0T_Motherboard_J_brd_V01_OCP.brd")
		(comment 1 "Grand Teton / footprint 3039 of 6105 (U2), pads 2917-3023 of 4677")
	)
	(layers
		(0 "F.Cu" signal "TOP")
		(4 "In1.Cu" signal "GND")
		(6 "In2.Cu" signal "IN1")
		(8 "In3.Cu" signal "GND1")
		(10 "In4.Cu" signal "IN2")
		(12 "In5.Cu" signal "GND2")
		(14 "In6.Cu" signal "IN3")
		(16 "In7.Cu" signal "GND3")
		(18 "In8.Cu" signal "VCC")
		(20 "In9.Cu" signal "VCC1")
		(22 "In10.Cu" signal "GND4")
		(24 "In11.Cu" signal "IN4")
		(26 "In12.Cu" signal "GND5")
		(28 "In13.Cu" signal "IN5")
		(30 "In14.Cu" signal "GND6")
		(32 "In15.Cu" signal "IN6")
		(34 "In16.Cu" signal "GND7")
		(2 "B.Cu" signal "BOTTOM")
		(9 "F.Adhes" user "F.Adhesive")
		(11 "B.Adhes" user "B.Adhesive")
		(13 "F.Paste" user "Package Geometry/Pastemask Top")
		(15 "B.Paste" user "Package Geometry/Pastemask Bottom")
		(5 "F.SilkS" user "Ref Des/Silkscreen Top")
		(7 "B.SilkS" user "Ref Des/Silkscreen Bottom")
		(1 "F.Mask" user "Board Geometry/Soldermask Top")
		(3 "B.Mask" user "Board Geometry/Soldermask Bottom")
		(17 "Dwgs.User" user "User.Drawings")
		(19 "Cmts.User" user "User.Comments")
		(21 "Eco1.User" user "User.Eco1")
		(23 "Eco2.User" user "User.Eco2")
		(25 "Edge.Cuts" user "Board Geometry/Outline")
		(27 "Margin" user)
		(31 "F.CrtYd" user "Package Geometry/Place Bound Top")
		(29 "B.CrtYd" user "Package Geometry/Place Bound Bottom")
		(35 "F.Fab" user "Ref Des/Assembly Top")
		(33 "B.Fab" user "Ref Des/Assembly Bottom")
	)
	(footprint ""
		(layer "F.Cu")
		(at 359.870248 -251.76988 90)
		(property "Reference" "U2"
			(at -74.416158 -44.488608 0)
			(unlocked yes)
			(layer "F.SilkS")
			(effects
				(font
					(size 1.6002 1.1938)
					(thickness 0.1524)
				)
				(justify left)
			)
		)
		(property "Value" ""
			(at 0 0 90)
			(layer "F.Fab")
			(effects
				(font
					(size 1.27 1.27)
				)
			)
		)
		(duplicate_pad_numbers_are_jumpers no)
		(pad "DM65" smd circle
			(at 16.263874 15.796514 270)
			(size 0.4318 0.4318)
			(layers "F.Cu" "F.Mask" "F.Paste")
			(net "GND")
		)
		(pad "DM67" smd circle
			(at 17.89176 15.796514 270)
			(size 0.4318 0.4318)
			(layers "F.Cu" "F.Mask" "F.Paste")
			(net "GND")
		)
		(pad "DM69" smd circle
			(at 19.519392 15.796514 270)
			(size 0.4318 0.4318)
			(layers "F.Cu" "F.Mask" "F.Paste")
			(net "GND")
		)
		(pad "DM71" smd circle
			(at 21.147278 15.796514 270)
			(size 0.4318 0.4318)
			(layers "F.Cu" "F.Mask" "F.Paste")
			(net "GND")
		)
		(pad "DM73" smd circle
			(at 22.77491 15.796514 270)
			(size 0.4318 0.4318)
			(layers "F.Cu" "F.Mask" "F.Paste")
			(net "GND")
		)
		(pad "DM75" smd circle
			(at 24.402796 15.796514 270)
			(size 0.4318 0.4318)
			(layers "F.Cu" "F.Mask" "F.Paste")
			(net "GND")
		)
		(pad "DM77" smd circle
			(at 26.030682 15.796514 270)
			(size 0.4318 0.4318)
			(layers "F.Cu" "F.Mask" "F.Paste")
			(net "GND")
		)
		(pad "DM79" smd circle
			(at 27.658314 15.796514 270)
			(size 0.4318 0.4318)
			(layers "F.Cu" "F.Mask" "F.Paste")
			(net "GND")
		)
		(pad "DM81" smd circle
			(at 29.2862 15.796514 270)
			(size 0.4318 0.4318)
			(layers "F.Cu" "F.Mask" "F.Paste")
			(net "Net_699")
		)
		(pad "DM83" smd circle
			(at 30.914086 15.796514 270)
			(size 0.4318 0.4318)
			(layers "F.Cu" "F.Mask" "F.Paste")
			(net "PVCCFA_EHV_FIVRA_CPU0")
		)
		(pad "DM85" smd circle
			(at 32.541718 15.796514 270)
			(size 0.4318 0.4318)
			(layers "F.Cu" "F.Mask" "F.Paste")
			(net "PVCCFA_EHV_FIVRA_CPU0")
		)
		(pad "DM87" smd circle
			(at 34.169604 15.796514 270)
			(size 0.4318 0.4318)
			(layers "F.Cu" "F.Mask" "F.Paste")
			(net "P5E_CPU0_PE3_TX_DN<6>")
		)
		(pad "DM89" smd circle
			(at 35.797236 15.796514 270)
			(size 0.4318 0.4318)
			(layers "F.Cu" "F.Mask" "F.Paste")
			(net "PVCCFA_EHV_FIVRA_CPU0")
		)
		(pad "DM91" smd oval
			(at 37.425122 15.796514)
			(size 0.381 0.4826)
			(drill
				(offset 0 -0.0508)
			)
			(layers "F.Cu" "F.Mask" "F.Paste")
			(net "P5E_CPU0_PE3_RX_DP<7>")
		)
		(pad "DN1" smd oval
			(at -37.425122 16.156686 180)
			(size 0.381 0.4826)
			(drill
				(offset 0 -0.0508)
			)
			(layers "F.Cu" "F.Mask" "F.Paste")
			(net "UPI_CPU1_CPU0_P0P1_DN<7>")
		)
		(pad "DN3" smd circle
			(at -35.797236 16.156686 270)
			(size 0.4318 0.4318)
			(layers "F.Cu" "F.Mask" "F.Paste")
			(net "PVCCFA_EHV_FIVRA_CPU0")
		)
		(pad "DN5" smd circle
			(at -34.169604 16.156686 270)
			(size 0.4318 0.4318)
			(layers "F.Cu" "F.Mask" "F.Paste")
			(net "UPI_CPU0_CPU1_P1P0_DP<6>")
		)
		(pad "DN7" smd circle
			(at -32.541718 16.156686 270)
			(size 0.4318 0.4318)
			(layers "F.Cu" "F.Mask" "F.Paste")
			(net "PVCCFA_EHV_FIVRA_CPU0")
		)
		(pad "DN9" smd circle
			(at -30.914086 16.156686 270)
			(size 0.4318 0.4318)
			(layers "F.Cu" "F.Mask" "F.Paste")
			(net "P5E_CPU0_PE2_RX_DN<8>")
		)
		(pad "DN11" smd circle
			(at -29.2862 16.156686 270)
			(size 0.4318 0.4318)
			(layers "F.Cu" "F.Mask" "F.Paste")
			(net "PVCCFA_EHV_FIVRA_CPU0")
		)
		(pad "DN13" smd circle
			(at -27.658314 16.156686 270)
			(size 0.4318 0.4318)
			(layers "F.Cu" "F.Mask" "F.Paste")
			(net "P5E_CPU0_PE2_TX_DN<8>")
		)
		(pad "DN15" smd circle
			(at -26.030682 16.156686 270)
			(size 0.4318 0.4318)
			(layers "F.Cu" "F.Mask" "F.Paste")
			(net "PVCCFA_EHV_FIVRA_CPU0")
		)
		(pad "DN17" smd circle
			(at -24.402796 16.156686 270)
			(size 0.4318 0.4318)
			(layers "F.Cu" "F.Mask" "F.Paste")
			(net "GND")
		)
		(pad "DN19" smd circle
			(at -22.77491 16.156686 270)
			(size 0.4318 0.4318)
			(layers "F.Cu" "F.Mask" "F.Paste")
			(net "M_H_CPU0_SB_DQ<23>")
		)
		(pad "DN21" smd circle
			(at -21.147278 16.156686 270)
			(size 0.4318 0.4318)
			(layers "F.Cu" "F.Mask" "F.Paste")
			(net "M_H_CPU0_SB_DQS_DP<7>")
		)
		(pad "DN23" smd circle
			(at -19.519392 16.156686 270)
			(size 0.4318 0.4318)
			(layers "F.Cu" "F.Mask" "F.Paste")
			(net "M_H_CPU0_SB_DQ<18>")
		)
		(pad "DN25" smd circle
			(at -17.89176 16.156686 270)
			(size 0.4318 0.4318)
			(layers "F.Cu" "F.Mask" "F.Paste")
			(net "M_G_CPU0_SB_DQ<15>")
		)
		(pad "DN27" smd circle
			(at -16.263874 16.156686 270)
			(size 0.4318 0.4318)
			(layers "F.Cu" "F.Mask" "F.Paste")
			(net "M_G_CPU0_SB_DQS_DN<6>")
		)
		(pad "DN29" smd circle
			(at -14.635988 16.156686 270)
			(size 0.4318 0.4318)
			(layers "F.Cu" "F.Mask" "F.Paste")
			(net "M_G_CPU0_SB_DQ<8>")
		)
		(pad "DN31" smd circle
			(at -13.008356 16.156686 270)
			(size 0.4318 0.4318)
			(layers "F.Cu" "F.Mask" "F.Paste")
			(net "M_G_CPU0_SB_DQ<7>")
		)
		(pad "DN33" smd circle
			(at -11.380724 16.156686 270)
			(size 0.4318 0.4318)
			(layers "F.Cu" "F.Mask" "F.Paste")
			(net "M_G_CPU0_SB_DQS_DP<5>")
		)
		(pad "DN35" smd circle
			(at -9.752838 16.156686 270)
			(size 0.4318 0.4318)
			(layers "F.Cu" "F.Mask" "F.Paste")
			(net "M_G_CPU0_SB_DQ<2>")
		)
		(pad "DN37" smd circle
			(at -8.124952 16.156686 270)
			(size 0.4318 0.4318)
			(layers "F.Cu" "F.Mask" "F.Paste")
			(net "M_H_CPU0_SB_CS_N<1>")
		)
		(pad "DN39" smd circle
			(at -6.49732 16.156686 270)
			(size 0.4318 0.4318)
			(layers "F.Cu" "F.Mask" "F.Paste")
			(net "GND")
		)
		(pad "DN41" smd circle
			(at -4.869434 16.156686 270)
			(size 0.4318 0.4318)
			(layers "F.Cu" "F.Mask" "F.Paste")
			(net "M_H_CPU0_SB_CA<3>")
		)
		(pad "DN43" smd circle
			(at -3.241802 16.156686 270)
			(size 0.4318 0.4318)
			(layers "F.Cu" "F.Mask" "F.Paste")
			(net "M_G_CPU0_SB_CA<0>")
		)
		(pad "DN45" smd circle
			(at -1.613916 16.156686 270)
			(size 0.4318 0.4318)
			(layers "F.Cu" "F.Mask" "F.Paste")
			(net "M_G_CPU0_CLK_DP<0>")
		)
		(pad "DN48" smd circle
			(at 2.427732 16.266668 270)
			(size 0.4318 0.4318)
			(layers "F.Cu" "F.Mask" "F.Paste")
			(net "M_F_CPU0_SA_RSP<0>")
		)
		(pad "DN50" smd circle
			(at 4.055618 16.266668 270)
			(size 0.4318 0.4318)
			(layers "F.Cu" "F.Mask" "F.Paste")
			(net "M_G_CPU0_SA_CA<5>")
		)
		(pad "DN52" smd circle
			(at 5.68325 16.266668 270)
			(size 0.4318 0.4318)
			(layers "F.Cu" "F.Mask" "F.Paste")
			(net "GND")
		)
		(pad "DN54" smd circle
			(at 7.311136 16.266668 270)
			(size 0.4318 0.4318)
			(layers "F.Cu" "F.Mask" "F.Paste")
			(net "M_G_CPU0_SA_CS_N<0>")
		)
		(pad "DN56" smd circle
			(at 8.939022 16.266668 270)
			(size 0.4318 0.4318)
			(layers "F.Cu" "F.Mask" "F.Paste")
			(net "M_G_CPU0_SA_CB<7>")
		)
		(pad "DN58" smd circle
			(at 10.566654 16.266668 270)
			(size 0.4318 0.4318)
			(layers "F.Cu" "F.Mask" "F.Paste")
			(net "M_G_CPU0_SA_DQS_DP<9>")
		)
		(pad "DN60" smd circle
			(at 12.19454 16.266668 270)
			(size 0.4318 0.4318)
			(layers "F.Cu" "F.Mask" "F.Paste")
			(net "M_G_CPU0_SA_CB<2>")
		)
		(pad "DN62" smd circle
			(at 13.822426 16.266668 270)
			(size 0.4318 0.4318)
			(layers "F.Cu" "F.Mask" "F.Paste")
			(net "M_G_CPU0_SA_DQ<31>")
		)
		(pad "DN64" smd circle
			(at 15.450058 16.266668 270)
			(size 0.4318 0.4318)
			(layers "F.Cu" "F.Mask" "F.Paste")
			(net "M_G_CPU0_SA_DQS_DP<8>")
		)
		(pad "DN66" smd circle
			(at 17.07769 16.266668 270)
			(size 0.4318 0.4318)
			(layers "F.Cu" "F.Mask" "F.Paste")
			(net "M_G_CPU0_SA_DQ<26>")
		)
		(pad "DN68" smd circle
			(at 18.705576 16.266668 270)
			(size 0.4318 0.4318)
			(layers "F.Cu" "F.Mask" "F.Paste")
			(net "M_G_CPU0_SA_DQ<15>")
		)
		(pad "DN70" smd circle
			(at 20.333462 16.266668 270)
			(size 0.4318 0.4318)
			(layers "F.Cu" "F.Mask" "F.Paste")
			(net "M_G_CPU0_SA_DQS_DP<6>")
		)
		(pad "DN72" smd circle
			(at 21.961094 16.266668 270)
			(size 0.4318 0.4318)
			(layers "F.Cu" "F.Mask" "F.Paste")
			(net "M_G_CPU0_SA_DQ<10>")
		)
		(pad "DN74" smd circle
			(at 23.58898 16.266668 270)
			(size 0.4318 0.4318)
			(layers "F.Cu" "F.Mask" "F.Paste")
			(net "M_H_CPU0_SA_DQ<7>")
		)
		(pad "DN76" smd circle
			(at 25.216612 16.266668 270)
			(size 0.4318 0.4318)
			(layers "F.Cu" "F.Mask" "F.Paste")
			(net "M_H_CPU0_SA_DQS_DP<5>")
		)
		(pad "DN78" smd circle
			(at 26.844498 16.266668 270)
			(size 0.4318 0.4318)
			(layers "F.Cu" "F.Mask" "F.Paste")
			(net "GND")
		)
		(pad "DN80" smd circle
			(at 28.472384 16.266668 270)
			(size 0.4318 0.4318)
			(layers "F.Cu" "F.Mask" "F.Paste")
			(net "Net_674")
		)
		(pad "DN82" smd circle
			(at 30.100016 16.266668 270)
			(size 0.4318 0.4318)
			(layers "F.Cu" "F.Mask" "F.Paste")
			(net "Net_678")
		)
		(pad "DN84" smd circle
			(at 31.727902 16.266668 270)
			(size 0.4318 0.4318)
			(layers "F.Cu" "F.Mask" "F.Paste")
			(net "GND")
		)
		(pad "DN86" smd circle
			(at 33.355534 16.266668 270)
			(size 0.4318 0.4318)
			(layers "F.Cu" "F.Mask" "F.Paste")
			(net "P5E_CPU0_PE3_TX_DP<6>")
		)
		(pad "DN88" smd circle
			(at 34.98342 16.266668 270)
			(size 0.4318 0.4318)
			(layers "F.Cu" "F.Mask" "F.Paste")
			(net "GND")
		)
		(pad "DN90" smd circle
			(at 36.611306 16.266668 270)
			(size 0.4318 0.4318)
			(layers "F.Cu" "F.Mask" "F.Paste")
			(net "P5E_CPU0_PE3_RX_DN<7>")
		)
		(pad "DP2" smd circle
			(at -36.611306 16.626332 270)
			(size 0.4318 0.4318)
			(layers "F.Cu" "F.Mask" "F.Paste")
			(net "UPI_CPU1_CPU0_P0P1_DP<7>")
		)
		(pad "DP4" smd circle
			(at -34.98342 16.626332 270)
			(size 0.4318 0.4318)
			(layers "F.Cu" "F.Mask" "F.Paste")
			(net "GND")
		)
		(pad "DP6" smd circle
			(at -33.355534 16.626332 270)
			(size 0.4318 0.4318)
			(layers "F.Cu" "F.Mask" "F.Paste")
			(net "UPI_CPU0_CPU1_P1P0_DN<6>")
		)
		(pad "DP8" smd circle
			(at -31.727902 16.626332 270)
			(size 0.4318 0.4318)
			(layers "F.Cu" "F.Mask" "F.Paste")
			(net "GND")
		)
		(pad "DP10" smd circle
			(at -30.100016 16.626332 270)
			(size 0.4318 0.4318)
			(layers "F.Cu" "F.Mask" "F.Paste")
			(net "P5E_CPU0_PE2_RX_DP<8>")
		)
		(pad "DP12" smd circle
			(at -28.472384 16.626332 270)
			(size 0.4318 0.4318)
			(layers "F.Cu" "F.Mask" "F.Paste")
			(net "GND")
		)
		(pad "DP14" smd circle
			(at -26.844498 16.626332 270)
			(size 0.4318 0.4318)
			(layers "F.Cu" "F.Mask" "F.Paste")
			(net "P5E_CPU0_PE2_TX_DN<9>")
		)
		(pad "DP16" smd circle
			(at -25.216612 16.626332 270)
			(size 0.4318 0.4318)
			(layers "F.Cu" "F.Mask" "F.Paste")
			(net "GND")
		)
		(pad "DP18" smd circle
			(at -23.58898 16.626332 270)
			(size 0.4318 0.4318)
			(layers "F.Cu" "F.Mask" "F.Paste")
			(net "GND")
		)
		(pad "DP20" smd circle
			(at -21.961094 16.626332 270)
			(size 0.4318 0.4318)
			(layers "F.Cu" "F.Mask" "F.Paste")
			(net "M_H_CPU0_SB_DQ<22>")
		)
		(pad "DP22" smd circle
			(at -20.333462 16.626332 270)
			(size 0.4318 0.4318)
			(layers "F.Cu" "F.Mask" "F.Paste")
			(net "M_H_CPU0_SB_DQ<19>")
		)
		(pad "DP24" smd circle
			(at -18.705576 16.626332 270)
			(size 0.4318 0.4318)
			(layers "F.Cu" "F.Mask" "F.Paste")
			(net "GND")
		)
		(pad "DP26" smd circle
			(at -17.07769 16.626332 270)
			(size 0.4318 0.4318)
			(layers "F.Cu" "F.Mask" "F.Paste")
			(net "M_G_CPU0_SB_DQ<14>")
		)
		(pad "DP28" smd circle
			(at -15.450058 16.626332 270)
			(size 0.4318 0.4318)
			(layers "F.Cu" "F.Mask" "F.Paste")
			(net "M_G_CPU0_SB_DQ<11>")
		)
		(pad "DP30" smd circle
			(at -13.822426 16.626332 270)
			(size 0.4318 0.4318)
			(layers "F.Cu" "F.Mask" "F.Paste")
			(net "GND")
		)
		(pad "DP32" smd circle
			(at -12.19454 16.626332 270)
			(size 0.4318 0.4318)
			(layers "F.Cu" "F.Mask" "F.Paste")
			(net "M_G_CPU0_SB_DQ<6>")
		)
		(pad "DP34" smd circle
			(at -10.566654 16.626332 270)
			(size 0.4318 0.4318)
			(layers "F.Cu" "F.Mask" "F.Paste")
			(net "M_G_CPU0_SB_DQ<3>")
		)
		(pad "DP36" smd circle
			(at -8.939022 16.626332 270)
			(size 0.4318 0.4318)
			(layers "F.Cu" "F.Mask" "F.Paste")
			(net "GND")
		)
		(pad "DP38" smd circle
			(at -7.311136 16.626332 270)
			(size 0.4318 0.4318)
			(layers "F.Cu" "F.Mask" "F.Paste")
			(net "M_H_CPU0_SB_CS_N<3>")
		)
		(pad "DP40" smd circle
			(at -5.68325 16.626332 270)
			(size 0.4318 0.4318)
			(layers "F.Cu" "F.Mask" "F.Paste")
			(net "M_H_CPU0_SB_CA<5>")
		)
		(pad "DP42" smd circle
			(at -4.055618 16.626332 270)
			(size 0.4318 0.4318)
			(layers "F.Cu" "F.Mask" "F.Paste")
			(net "GND")
		)
		(pad "DP44" smd circle
			(at -2.427732 16.626332 270)
			(size 0.4318 0.4318)
			(layers "F.Cu" "F.Mask" "F.Paste")
			(net "M_G_CPU0_SB_CA<1>")
		)
		(pad "DP47" smd circle
			(at 1.613916 16.736314 270)
			(size 0.4318 0.4318)
			(layers "F.Cu" "F.Mask" "F.Paste")
			(net "M_F_CPU0_SA_RSP<1>")
		)
		(pad "DP49" smd circle
			(at 3.241802 16.736314 270)
			(size 0.4318 0.4318)
			(layers "F.Cu" "F.Mask" "F.Paste")
			(net "GND")
		)
		(pad "DP51" smd circle
			(at 4.869434 16.736314 270)
			(size 0.4318 0.4318)
			(layers "F.Cu" "F.Mask" "F.Paste")
			(net "M_G_CPU0_SA_CA<3>")
		)
		(pad "DP53" smd circle
			(at 6.49732 16.736314 270)
			(size 0.4318 0.4318)
			(layers "F.Cu" "F.Mask" "F.Paste")
			(net "M_G_CPU0_SA_CS_N<1>")
		)
		(pad "DP55" smd circle
			(at 8.124952 16.736314 270)
			(size 0.4318 0.4318)
			(layers "F.Cu" "F.Mask" "F.Paste")
			(net "GND")
		)
		(pad "DP57" smd circle
			(at 9.752838 16.736314 270)
			(size 0.4318 0.4318)
			(layers "F.Cu" "F.Mask" "F.Paste")
			(net "M_G_CPU0_SA_CB<6>")
		)
		(pad "DP59" smd circle
			(at 11.380724 16.736314 270)
			(size 0.4318 0.4318)
			(layers "F.Cu" "F.Mask" "F.Paste")
			(net "M_G_CPU0_SA_CB<3>")
		)
		(pad "DP61" smd circle
			(at 13.008356 16.736314 270)
			(size 0.4318 0.4318)
			(layers "F.Cu" "F.Mask" "F.Paste")
			(net "GND")
		)
		(pad "DP63" smd circle
			(at 14.635988 16.736314 270)
			(size 0.4318 0.4318)
			(layers "F.Cu" "F.Mask" "F.Paste")
			(net "M_G_CPU0_SA_DQ<30>")
		)
		(pad "DP65" smd circle
			(at 16.263874 16.736314 270)
			(size 0.4318 0.4318)
			(layers "F.Cu" "F.Mask" "F.Paste")
			(net "M_G_CPU0_SA_DQ<27>")
		)
		(pad "DP67" smd circle
			(at 17.89176 16.736314 270)
			(size 0.4318 0.4318)
			(layers "F.Cu" "F.Mask" "F.Paste")
			(net "GND")
		)
		(pad "DP69" smd circle
			(at 19.519392 16.736314 270)
			(size 0.4318 0.4318)
			(layers "F.Cu" "F.Mask" "F.Paste")
			(net "M_G_CPU0_SA_DQ<14>")
		)
		(pad "DP71" smd circle
			(at 21.147278 16.736314 270)
			(size 0.4318 0.4318)
			(layers "F.Cu" "F.Mask" "F.Paste")
			(net "M_G_CPU0_SA_DQ<11>")
		)
		(pad "DP73" smd circle
			(at 22.77491 16.736314 270)
			(size 0.4318 0.4318)
			(layers "F.Cu" "F.Mask" "F.Paste")
			(net "GND")
		)
		(pad "DP75" smd circle
			(at 24.402796 16.736314 270)
			(size 0.4318 0.4318)
			(layers "F.Cu" "F.Mask" "F.Paste")
			(net "M_H_CPU0_SA_DQ<6>")
		)
		(pad "DP77" smd circle
			(at 26.030682 16.736314 270)
			(size 0.4318 0.4318)
			(layers "F.Cu" "F.Mask" "F.Paste")
			(net "M_H_CPU0_SA_DQ<3>")
		)
		(pad "DP79" smd circle
			(at 27.658314 16.736314 270)
			(size 0.4318 0.4318)
			(layers "F.Cu" "F.Mask" "F.Paste")
			(net "Net_679")
		)
		(pad "DP81" smd circle
			(at 29.2862 16.736314 270)
			(size 0.4318 0.4318)
			(layers "F.Cu" "F.Mask" "F.Paste")
			(net "GND")
		)
		(pad "DP83" smd circle
			(at 30.914086 16.736314 270)
			(size 0.4318 0.4318)
			(layers "F.Cu" "F.Mask" "F.Paste")
			(net "Net_654")
		)
		(pad "DP85" smd circle
			(at 32.541718 16.736314 270)
			(size 0.4318 0.4318)
			(layers "F.Cu" "F.Mask" "F.Paste")
			(net "P5E_CPU0_PE3_TX_DN<5>")
		)
		(pad "DP87" smd circle
			(at 34.169604 16.736314 270)
			(size 0.4318 0.4318)
			(layers "F.Cu" "F.Mask" "F.Paste")
			(net "GND")
		)
		(pad "DP89" smd circle
			(at 35.797236 16.736314 270)
			(size 0.4318 0.4318)
			(layers "F.Cu" "F.Mask" "F.Paste")
			(net "P5E_CPU0_PE3_RX_DN<6>")
		)
		(pad "DP91" smd oval
			(at 37.425122 16.736314)
			(size 0.381 0.4826)
			(drill
				(offset 0 -0.0508)
			)
			(layers "F.Cu" "F.Mask" "F.Paste")
			(net "GND")
		)
		(pad "DR1" smd oval
			(at -37.425122 17.096486 180)
			(size 0.381 0.4826)
			(drill
				(offset 0 -0.0508)
			)
			(layers "F.Cu" "F.Mask" "F.Paste")
			(net "GND")
		)
		(pad "DR3" smd circle
			(at -35.797236 17.096486 270)
			(size 0.4318 0.4318)
			(layers "F.Cu" "F.Mask" "F.Paste")
			(net "UPI_CPU1_CPU0_P0P1_DP<6>")
		)
		(pad "DR5" smd circle
			(at -34.169604 17.096486 270)
			(size 0.4318 0.4318)
			(layers "F.Cu" "F.Mask" "F.Paste")
			(net "GND")
		)
	)
)
